(kicad_pcb
	(version 20241229)
	(generator "pcbnew")
	(generator_version "9.0")
	(general
		(thickness 1.61)
		(legacy_teardrops no)
	)
	(paper "A3")
	(title_block
		(title "RDIMM DDR5 Tester")
		(date "2026-05-21")
		(rev "2.2.0")
		(company "Antmicro")
		(comment 9 "footprints 253-257 of 796")
	)
	(layers
		(0 "F.Cu" signal)
		(4 "In1.Cu" power)
		(6 "In2.Cu" mixed)
		(8 "In3.Cu" power)
		(10 "In4.Cu" mixed)
		(12 "In5.Cu" power)
		(14 "In6.Cu" mixed)
		(16 "In7.Cu" power)
		(18 "In8.Cu" power)
		(20 "In9.Cu" mixed)
		(22 "In10.Cu" power)
		(2 "B.Cu" signal)
		(9 "F.Adhes" user "F.Adhesive")
		(11 "B.Adhes" user "B.Adhesive")
		(13 "F.Paste" user)
		(15 "B.Paste" user)
		(5 "F.SilkS" user "F.Silkscreen")
		(7 "B.SilkS" user "B.Silkscreen")
		(1 "F.Mask" user)
		(3 "B.Mask" user)
		(17 "Dwgs.User" user "User.Drawings")
		(19 "Cmts.User" user "User.Comments")
		(21 "Eco1.User" user "User.Eco1")
		(23 "Eco2.User" user "User.Eco2")
		(25 "Edge.Cuts" user)
		(27 "Margin" user)
		(31 "F.CrtYd" user "F.Courtyard")
		(29 "B.CrtYd" user "B.Courtyard")
		(35 "F.Fab" user)
		(33 "B.Fab" user)
	)
	(footprint "antmicro-footprints:C_0603_1608Metric"
		(layer "F.Cu")
		(at 226.639999 170.104999)
		(descr "Capacitor SMD 0603")
		(tags "capacitor 0603")
		(property "Reference" "C267"
			(at -1.36 -2.155 0)
			(layer "F.SilkS")
			(effects
				(font
					(size 0.7 0.7)
					(thickness 0.15)
				)
				(justify left bottom)
			)
		)
		(property "Value" "C_22u_0603"
			(at -1.42757 1.770288 0)
			(layer "F.Fab")
			(effects
				(font
					(size 0.7 0.7)
					(thickness 0.15)
				)
				(justify left bottom)
			)
		)
		(property "Datasheet" "https://www.murata.com/products/productdetail?partno=GRM188R60J226MEA0%23"
			(at 0 0 0)
			(layer "F.Fab")
			(hide yes)
			(effects
				(font
					(size 1.27 1.27)
					(thickness 0.15)
				)
			)
		)
		(property "Manufacturer" "Murata"
			(at 0 0 0)
			(unlocked yes)
			(layer "F.Fab")
			(hide yes)
			(effects
				(font
					(size 1 1)
					(thickness 0.15)
				)
			)
		)
		(property "MPN" "GRM188R60J226MEA0D"
			(at 0 0 0)
			(unlocked yes)
			(layer "F.Fab")
			(hide yes)
			(effects
				(font
					(size 1 1)
					(thickness 0.15)
				)
			)
		)
		(property "Val" "22u"
			(at 0 0 0)
			(unlocked yes)
			(layer "F.Fab")
			(hide yes)
			(effects
				(font
					(size 1 1)
					(thickness 0.15)
				)
			)
		)
		(property "License" "Apache-2.0"
			(at 0 0 0)
			(unlocked yes)
			(layer "F.Fab")
			(hide yes)
			(effects
				(font
					(size 1 1)
					(thickness 0.15)
				)
			)
		)
		(property "Author" "Antmicro"
			(at 0 0 0)
			(unlocked yes)
			(layer "F.Fab")
			(hide yes)
			(effects
				(font
					(size 1 1)
					(thickness 0.15)
				)
			)
		)
		(property "Voltage" ""
			(at 0 0 0)
			(unlocked yes)
			(layer "F.Fab")
			(hide yes)
			(effects
				(font
					(size 1 1)
					(thickness 0.15)
				)
			)
		)
		(property "Dielectric" ""
			(at 0 0 0)
			(unlocked yes)
			(layer "F.Fab")
			(hide yes)
			(effects
				(font
					(size 1 1)
					(thickness 0.15)
				)
			)
		)
		(sheetname "/Supply/DC-DC VCCINT/")
		(sheetfile "dc-dc-vccint.kicad_sch")
		(attr smd)
		(fp_line
			(start -0.15 -0.4)
			(end 0.15 -0.4)
			(stroke
				(width 0.15)
				(type solid)
			)
			(layer "F.SilkS")
		)
		(fp_line
			(start -0.15 0.4)
			(end 0.15 0.4)
			(stroke
				(width 0.15)
				(type solid)
			)
			(layer "F.SilkS")
		)
		(fp_rect
			(start -1.25 -0.65)
			(end 1.25 0.65)
			(stroke
				(width 0.05)
				(type solid)
			)
			(fill no)
			(layer "F.CrtYd")
		)
		(fp_rect
			(start -0.8 -0.4)
			(end 0.8 0.4)
			(stroke
				(width 0.15)
				(type solid)
			)
			(fill no)
			(layer "F.Fab")
		)
		(fp_text user "${REFERENCE}"
			(at -1.682 3.895 0)
			(layer "F.Fab")
			(effects
				(font
					(size 0.7 0.7)
					(thickness 0.15)
				)
				(justify left bottom)
			)
		)
		(fp_text user "Author: Antmicro"
			(at -1.682 4.894 0)
			(layer "F.Fab")
			(effects
				(font
					(size 0.7 0.7)
					(thickness 0.15)
				)
				(justify left bottom)
			)
		)
		(fp_text user "License: Apache-2.0"
			(at -1.682 5.895 0)
			(layer "F.Fab")
			(effects
				(font
					(size 0.7 0.7)
					(thickness 0.15)
				)
				(justify left bottom)
			)
		)
		(pad "1" smd roundrect
			(at -0.7 0)
			(size 0.8 1)
			(layers "F.Cu" "F.Mask" "F.Paste")
			(roundrect_rratio 0.2)
			(net 1 "GND")
			(pintype "passive")
		)
		(pad "2" smd roundrect
			(at 0.7 0)
			(size 0.8 1)
			(layers "F.Cu" "F.Mask" "F.Paste")
			(roundrect_rratio 0.2)
			(net 224 "/Supply/DC-DC VCCINT/0V85_REG1")
			(pintype "passive")
		)
	)
	(footprint "antmicro-footprints:R_0402_1005Metric"
		(layer "F.Cu")
		(at 149.374499 173.249 -90)
		(descr "Resistor SMD 0402")
		(tags "resistor SMD 0402")
		(property "Reference" "R92"
			(at 0.921 -0.485501 90)
			(layer "F.SilkS")
			(effects
				(font
					(size 0.7 0.7)
					(thickness 0.15)
				)
				(justify right bottom)
			)
		)
		(property "Value" "R_0R_0402"
			(at -1.011843 1.772047 90)
			(layer "F.Fab")
			(effects
				(font
					(size 0.7 0.7)
					(thickness 0.15)
				)
				(justify right bottom)
			)
		)
		(property "Datasheet" "https://industrial.panasonic.com/cdbs/www-data/pdf/RDA0000/AOA0000C301.pdf"
			(at 0 0 270)
			(layer "F.Fab")
			(hide yes)
			(effects
				(font
					(size 1.27 1.27)
					(thickness 0.15)
				)
			)
		)
		(property "Manufacturer" "Panasonic"
			(at 0 0 270)
			(unlocked yes)
			(layer "F.Fab")
			(hide yes)
			(effects
				(font
					(size 1 1)
					(thickness 0.15)
				)
			)
		)
		(property "MPN" "ERJ2GE0R00X"
			(at 0 0 270)
			(unlocked yes)
			(layer "F.Fab")
			(hide yes)
			(effects
				(font
					(size 1 1)
					(thickness 0.15)
				)
			)
		)
		(property "Val" "0R"
			(at 0 0 270)
			(unlocked yes)
			(layer "F.Fab")
			(hide yes)
			(effects
				(font
					(size 1 1)
					(thickness 0.15)
				)
			)
		)
		(property "License" "Apache-2.0"
			(at 0 0 270)
			(unlocked yes)
			(layer "F.Fab")
			(hide yes)
			(effects
				(font
					(size 1 1)
					(thickness 0.15)
				)
			)
		)
		(property "Author" "Antmicro"
			(at 0 0 270)
			(unlocked yes)
			(layer "F.Fab")
			(hide yes)
			(effects
				(font
					(size 1 1)
					(thickness 0.15)
				)
			)
		)
		(property "Tolerance" "~"
			(at 0 0 270)
			(unlocked yes)
			(layer "F.Fab")
			(hide yes)
			(effects
				(font
					(size 1 1)
					(thickness 0.15)
				)
			)
		)
		(property "Current" "1A"
			(at 0 0 270)
			(unlocked yes)
			(layer "F.Fab")
			(hide yes)
			(effects
				(font
					(size 1 1)
					(thickness 0.15)
				)
			)
		)
		(sheetname "/Debug FTDI + VNA/")
		(sheetfile "debug-ftdi.kicad_sch")
		(attr smd)
		(fp_rect
			(start -0.925 -0.47)
			(end 0.925 0.47)
			(stroke
				(width 0.05)
				(type default)
			)
			(fill no)
			(layer "F.CrtYd")
		)
		(fp_rect
			(start -0.5 -0.25)
			(end 0.5 0.25)
			(stroke
				(width 0.15)
				(type solid)
			)
			(fill no)
			(layer "F.Fab")
		)
		(fp_text user "Author: Antmicro"
			(at -0.95 4.169 270)
			(layer "F.Fab")
			(effects
				(font
					(size 0.7 0.7)
					(thickness 0.15)
				)
				(justify left bottom)
			)
		)
		(fp_text user "License: Apache-2.0"
			(at -0.95 5.169 270)
			(layer "F.Fab")
			(effects
				(font
					(size 0.7 0.7)
					(thickness 0.15)
				)
				(justify left bottom)
			)
		)
		(fp_text user "${REFERENCE}"
			(at -0.95 3.168 270)
			(layer "F.Fab")
			(effects
				(font
					(size 0.7 0.7)
					(thickness 0.15)
				)
				(justify left bottom)
			)
		)
		(pad "1" smd roundrect
			(at -0.48 0 270)
			(size 0.59 0.64)
			(layers "F.Cu" "F.Mask" "F.Paste")
			(roundrect_rratio 0.25)
			(net 447 "/Debug FTDI + VNA/FTDI_SCL")
			(pintype "passive")
		)
		(pad "2" smd roundrect
			(at 0.48 0 270)
			(size 0.59 0.64)
			(layers "F.Cu" "F.Mask" "F.Paste")
			(roundrect_rratio 0.25)
			(net 526 "/Debug FTDI + VNA/FTDI.SCL")
			(pintype "passive")
		)
	)
	(footprint "antmicro-footprints:Conn_JST_SH_1x4_BM04B-SRSS-TB-LF-SN"
		(layer "F.Cu")
		(at 227.15 160.341001 180)
		(property "Reference" "J8"
			(at 1.9 2.65 0)
			(layer "F.SilkS")
			(effects
				(font
					(size 0.7 0.7)
					(thickness 0.15)
				)
				(justify right top)
			)
		)
		(property "Value" "JST_SH_1x4_BM04B-SRSS-TB-LF-SN"
			(at 0 3.1 0)
			(layer "F.Fab")
			(effects
				(font
					(size 0.7 0.7)
					(thickness 0.15)
				)
				(justify right top)
			)
		)
		(property "Datasheet" "https://www.jst-mfg.com/product/pdf/eng/eSH.pdf"
			(at 0 0 0)
			(layer "F.Fab")
			(hide yes)
			(effects
				(font
					(size 1.27 1.27)
					(thickness 0.15)
				)
			)
		)
		(property "MPN" "BM04B-SRSS-TB(LF)(SN) "
			(at 0 0 180)
			(unlocked yes)
			(layer "F.Fab")
			(hide yes)
			(effects
				(font
					(size 1 1)
					(thickness 0.15)
				)
			)
		)
		(property "Manufacturer" "JST Automotive Connectors"
			(at 0 0 180)
			(unlocked yes)
			(layer "F.Fab")
			(hide yes)
			(effects
				(font
					(size 1 1)
					(thickness 0.15)
				)
			)
		)
		(property "Author" "Antmicro"
			(at 0 0 180)
			(unlocked yes)
			(layer "F.Fab")
			(hide yes)
			(effects
				(font
					(size 1 1)
					(thickness 0.15)
				)
			)
		)
		(property "License" "Apache-2.0"
			(at 0 0 180)
			(unlocked yes)
			(layer "F.Fab")
			(hide yes)
			(effects
				(font
					(size 1 1)
					(thickness 0.15)
				)
			)
		)
		(sheetname "/Supply/")
		(sheetfile "supply.kicad_sch")
		(attr smd)
		(fp_line
			(start 1.774 -1.7)
			(end 1.774 1.702)
			(stroke
				(width 0.15)
				(type solid)
			)
			(layer "F.SilkS")
		)
		(fp_line
			(start -0.251 2.999)
			(end -1.125 2.999)
			(stroke
				(width 0.15)
				(type solid)
			)
			(layer "F.SilkS")
		)
		(fp_line
			(start -0.251 -2.999)
			(end -1.125 -2.999)
			(stroke
				(width 0.15)
				(type solid)
			)
			(layer "F.SilkS")
		)
		(fp_line
			(start -1.125 2.999)
			(end -1.125 2.201)
			(stroke
				(width 0.15)
				(type solid)
			)
			(layer "F.SilkS")
		)
		(fp_line
			(start -1.125 -2.999)
			(end -1.125 -2.201)
			(stroke
				(width 0.15)
				(type solid)
			)
			(layer "F.SilkS")
		)
		(fp_circle
			(center -1.6 -2.1)
			(end -1.55 -2.1)
			(stroke
				(width 0.15)
				(type solid)
			)
			(fill yes)
			(layer "F.SilkS")
		)
		(fp_rect
			(start -2.05 -3.95)
			(end 2.05 3.95)
			(stroke
				(width 0.05)
				(type solid)
			)
			(fill no)
			(layer "F.CrtYd")
		)
		(fp_rect
			(start -1.8 -3)
			(end 1.8 3)
			(stroke
				(width 0.15)
				(type solid)
			)
			(fill no)
			(layer "F.Fab")
		)
		(fp_text user "${REFERENCE}"
			(at -3.25 8.2 180)
			(layer "F.Fab")
			(effects
				(font
					(size 0.7 0.7)
					(thickness 0.15)
				)
				(justify left bottom)
			)
		)
		(fp_text user "License: Apache-2.0"
			(at -3.25 9.4 180)
			(layer "F.Fab")
			(effects
				(font
					(size 0.7 0.7)
					(thickness 0.15)
				)
				(justify left bottom)
			)
		)
		(fp_text user "Author: Antmicro"
			(at -3.25 7 180)
			(layer "F.Fab")
			(effects
				(font
					(size 0.7 0.7)
					(thickness 0.15)
				)
				(justify left bottom)
			)
		)
		(pad "1" smd roundrect
			(at -1.45 -1.5 90)
			(size 0.6 1.55)
			(layers "F.Cu" "F.Mask" "F.Paste")
			(roundrect_rratio 0.25)
			(net 1 "GND")
			(pintype "passive")
		)
		(pad "2" smd roundrect
			(at -1.45 -0.5 90)
			(size 0.6 1.55)
			(layers "F.Cu" "F.Mask" "F.Paste")
			(roundrect_rratio 0.25)
			(net 152 "+5V")
			(pintype "passive")
		)
		(pad "3" smd roundrect
			(at -1.45 0.5 90)
			(size 0.6 1.55)
			(layers "F.Cu" "F.Mask" "F.Paste")
			(roundrect_rratio 0.25)
			(net 251 "unconnected-(J8-Pad3)")
			(pintype "passive+no_connect")
		)
		(pad "4" smd roundrect
			(at -1.45 1.5 90)
			(size 0.6 1.55)
			(layers "F.Cu" "F.Mask" "F.Paste")
			(roundrect_rratio 0.25)
			(net 250 "Net-(Q15-D)")
			(pintype "passive")
		)
		(pad "MP" smd roundrect
			(at 1.075 -2.8 90)
			(size 1.2 1.8)
			(layers "F.Cu" "F.Mask" "F.Paste")
			(roundrect_rratio 0.25)
			(net 1 "GND")
			(pintype "passive")
		)
		(pad "MP" smd roundrect
			(at 1.075 2.8 90)
			(size 1.2 1.8)
			(layers "F.Cu" "F.Mask" "F.Paste")
			(roundrect_rratio 0.25)
			(net 1 "GND")
			(pintype "passive")
		)
	)
	(footprint "antmicro-footprints:SOD-523"
		(layer "F.Cu")
		(at 257.8 138.825 90)
		(property "Reference" "D9"
			(at 0 -0.75 90)
			(layer "F.SilkS")
			(effects
				(font
					(size 0.7 0.7)
					(thickness 0.15)
				)
				(justify left bottom)
			)
		)
		(property "Value" "PESD5V0X1UB"
			(at 0 1.499 90)
			(layer "F.Fab")
			(effects
				(font
					(size 0.7 0.7)
					(thickness 0.15)
				)
				(justify left bottom)
			)
		)
		(property "Datasheet" "https://assets.nexperia.com/documents/data-sheet/PESD5V0X1UB.pdf"
			(at 0 0 90)
			(layer "F.Fab")
			(hide yes)
			(effects
				(font
					(size 1.27 1.27)
					(thickness 0.15)
				)
			)
		)
		(property "MPN" "PESD5V0X1UB,135"
			(at 0 0 90)
			(unlocked yes)
			(layer "F.Fab")
			(hide yes)
			(effects
				(font
					(size 1 1)
					(thickness 0.15)
				)
			)
		)
		(property "Manufacturer" "Nexperia"
			(at 0 0 90)
			(unlocked yes)
			(layer "F.Fab")
			(hide yes)
			(effects
				(font
					(size 1 1)
					(thickness 0.15)
				)
			)
		)
		(property "Author" "Antmicro"
			(at 0 0 90)
			(unlocked yes)
			(layer "F.Fab")
			(hide yes)
			(effects
				(font
					(size 1 1)
					(thickness 0.15)
				)
			)
		)
		(property "License" "Apache-2.0"
			(at 0 0 90)
			(unlocked yes)
			(layer "F.Fab")
			(hide yes)
			(effects
				(font
					(size 1 1)
					(thickness 0.15)
				)
			)
		)
		(sheetname "/FPGA Config/")
		(sheetfile "fpga-config.kicad_sch")
		(attr smd)
		(fp_line
			(start -0.35 -0.5)
			(end -0.35 0.5)
			(stroke
				(width 0.15)
				(type solid)
			)
			(layer "F.SilkS")
		)
		(fp_rect
			(start -1 -0.6)
			(end 1 0.6)
			(stroke
				(width 0.05)
				(type solid)
			)
			(fill no)
			(layer "F.CrtYd")
		)
		(fp_line
			(start 0.65 -0.425)
			(end 0.65 0.423)
			(stroke
				(width 0.15)
				(type solid)
			)
			(layer "F.Fab")
		)
		(fp_line
			(start -0.652 -0.425)
			(end 0.65 -0.425)
			(stroke
				(width 0.15)
				(type solid)
			)
			(layer "F.Fab")
		)
		(fp_line
			(start -0.35 -0.4)
			(end -0.35 0.4)
			(stroke
				(width 0.15)
				(type solid)
			)
			(layer "F.Fab")
		)
		(fp_line
			(start -0.652 0.423)
			(end -0.652 -0.425)
			(stroke
				(width 0.15)
				(type solid)
			)
			(layer "F.Fab")
		)
		(fp_line
			(start -0.652 0.423)
			(end 0.65 0.423)
			(stroke
				(width 0.15)
				(type solid)
			)
			(layer "F.Fab")
		)
		(fp_text user "Author: Antmicro"
			(at -1.276 4.7 90)
			(layer "F.Fab")
			(effects
				(font
					(size 0.7 0.7)
					(thickness 0.15)
				)
				(justify left bottom)
			)
		)
		(fp_text user "License: Apache-2.0"
			(at -1.276 5.9 90)
			(layer "F.Fab")
			(effects
				(font
					(size 0.7 0.7)
					(thickness 0.15)
				)
				(justify left bottom)
			)
		)
		(fp_text user "${REFERENCE}"
			(at -1.276 3.499 90)
			(layer "F.Fab")
			(effects
				(font
					(size 0.7 0.7)
					(thickness 0.15)
				)
				(justify left bottom)
			)
		)
		(pad "1" smd roundrect
			(at -0.701 0 90)
			(size 0.5 0.6)
			(layers "F.Cu" "F.Mask" "F.Paste")
			(roundrect_rratio 0.25)
			(net 357 "/FPGA Config/PROGRAM_B")
			(pinfunction "C")
			(pintype "passive")
		)
		(pad "2" smd roundrect
			(at 0.699 0 90)
			(size 0.5 0.6)
			(layers "F.Cu" "F.Mask" "F.Paste")
			(roundrect_rratio 0.25)
			(net 1 "GND")
			(pinfunction "A")
			(pintype "passive")
		)
	)
	(footprint "antmicro-footprints:C_0603_1608Metric"
		(layer "F.Cu")
		(at 109.273499 139.299 90)
		(descr "Capacitor SMD 0603")
		(tags "capacitor 0603")
		(property "Reference" "C109"
			(at -1.42757 -1.000252 90)
			(layer "F.SilkS")
			(effects
				(font
					(size 0.7 0.7)
					(thickness 0.15)
				)
				(justify left bottom)
			)
		)
		(property "Value" "C_10u_25V_0603"
			(at -1.42757 1.770288 90)
			(layer "F.Fab")
			(effects
				(font
					(size 0.7 0.7)
					(thickness 0.15)
				)
				(justify left bottom)
			)
		)
		(property "Datasheet" "https://product.tdk.com/en/search/capacitor/ceramic/mlcc/info?part_no=C1608X5R1E106M080AC"
			(at 0 0 90)
			(layer "F.Fab")
			(hide yes)
			(effects
				(font
					(size 1.27 1.27)
					(thickness 0.15)
				)
			)
		)
		(property "Manufacturer" "TDK"
			(at 0 0 90)
			(unlocked yes)
			(layer "F.Fab")
			(hide yes)
			(effects
				(font
					(size 1 1)
					(thickness 0.15)
				)
			)
		)
		(property "MPN" "C1608X5R1E106M080AC"
			(at 0 0 90)
			(unlocked yes)
			(layer "F.Fab")
			(hide yes)
			(effects
				(font
					(size 1 1)
					(thickness 0.15)
				)
			)
		)
		(property "Val" "10u"
			(at 0 0 90)
			(unlocked yes)
			(layer "F.Fab")
			(hide yes)
			(effects
				(font
					(size 1 1)
					(thickness 0.15)
				)
			)
		)
		(property "License" "Apache-2.0"
			(at 0 0 90)
			(unlocked yes)
			(layer "F.Fab")
			(hide yes)
			(effects
				(font
					(size 1 1)
					(thickness 0.15)
				)
			)
		)
		(property "Author" "Antmicro"
			(at 0 0 90)
			(unlocked yes)
			(layer "F.Fab")
			(hide yes)
			(effects
				(font
					(size 1 1)
					(thickness 0.15)
				)
			)
		)
		(property "Voltage" "25V"
			(at 0 0 90)
			(unlocked yes)
			(layer "F.Fab")
			(hide yes)
			(effects
				(font
					(size 1 1)
					(thickness 0.15)
				)
			)
		)
		(property "Dielectric" ""
			(at 0 0 90)
			(unlocked yes)
			(layer "F.Fab")
			(hide yes)
			(effects
				(font
					(size 1 1)
					(thickness 0.15)
				)
			)
		)
		(sheetname "/Debug FTDI + VNA/")
		(sheetfile "debug-ftdi.kicad_sch")
		(attr smd)
		(fp_line
			(start -0.15 -0.4)
			(end 0.15 -0.4)
			(stroke
				(width 0.15)
				(type solid)
			)
			(layer "F.SilkS")
		)
		(fp_line
			(start -0.15 0.4)
			(end 0.15 0.4)
			(stroke
				(width 0.15)
				(type solid)
			)
			(layer "F.SilkS")
		)
		(fp_rect
			(start -1.25 -0.65)
			(end 1.25 0.65)
			(stroke
				(width 0.05)
				(type solid)
			)
			(fill no)
			(layer "F.CrtYd")
		)
		(fp_rect
			(start -0.8 -0.4)
			(end 0.8 0.4)
			(stroke
				(width 0.15)
				(type solid)
			)
			(fill no)
			(layer "F.Fab")
		)
		(fp_text user "License: Apache-2.0"
			(at -1.682 5.895 90)
			(layer "F.Fab")
			(effects
				(font
					(size 0.7 0.7)
					(thickness 0.15)
				)
				(justify left bottom)
			)
		)
		(fp_text user "${REFERENCE}"
			(at -1.682 3.895 90)
			(layer "F.Fab")
			(effects
				(font
					(size 0.7 0.7)
					(thickness 0.15)
				)
				(justify left bottom)
			)
		)
		(fp_text user "Author: Antmicro"
			(at -1.682 4.894 90)
			(layer "F.Fab")
			(effects
				(font
					(size 0.7 0.7)
					(thickness 0.15)
				)
				(justify left bottom)
			)
		)
		(pad "1" smd roundrect
			(at -0.7 0 90)
			(size 0.8 1)
			(layers "F.Cu" "F.Mask" "F.Paste")
			(roundrect_rratio 0.2)
			(net 1 "GND")
			(pintype "passive")
		)
		(pad "2" smd roundrect
			(at 0.7 0 90)
			(size 0.8 1)
			(layers "F.Cu" "F.Mask" "F.Paste")
			(roundrect_rratio 0.2)
			(net 2 "/Debug FTDI + VNA/VBUS")
			(pintype "passive")
		)
	)
)
